# BASEBOARD_FAB2 (Tioga Pass) — schematic netlist excerpt (pin names and nets, part order shuffled) for the footprints in the layout excerpt that follows; sources: Cadence DE-HDL packaged netlist, KiCad conversion of Wiwynn_Tioga_Pass_MB.brd

R3N14  RES  49.9 1% EMPTY  pkg 0402  page 118 : A = H_PM_SYNC_GTL ; B = GND
R2T52  RES  2.2 1.0% CHIP  pkg 0603  page 101 : A = P3V3_STBY_MNG ; B = P3V3_STBY_MNG_RMII

(kicad_pcb
	(version 20260206)
	(generator "pcbnew")
	(generator_version "10.0")
	(general
		(thickness 1.6)
		(legacy_teardrops no)
	)
	(paper "A4")
	(title_block
		(title "Wiwynn_Tioga_Pass_MB.brd")
		(comment 1 "Tioga Pass / footprints 4286-4287 of 4770")
	)
	(layers
		(0 "F.Cu" signal "TOP")
		(4 "In1.Cu" signal "L2GND")
		(6 "In2.Cu" signal "L3")
		(8 "In3.Cu" signal "L4GND")
		(10 "In4.Cu" signal "L5")
		(12 "In5.Cu" signal "L6GND")
		(14 "In6.Cu" signal "L7VCC")
		(16 "In7.Cu" signal "L8VCC")
		(18 "In8.Cu" signal "L9GND")
		(20 "In9.Cu" signal "L10")
		(22 "In10.Cu" signal "L11GND")
		(24 "In11.Cu" signal "L12")
		(26 "In12.Cu" signal "L13GND")
		(2 "B.Cu" signal "BOTTOM")
		(9 "F.Adhes" user "F.Adhesive")
		(11 "B.Adhes" user "B.Adhesive")
		(13 "F.Paste" user "Package Geometry/Pastemask Top")
		(15 "B.Paste" user "Package Geometry/Pastemask Bottom")
		(5 "F.SilkS" user "Ref Des/Silkscreen Top")
		(7 "B.SilkS" user "Ref Des/Silkscreen Bottom")
		(1 "F.Mask" user "Board Geometry/Soldermask Top")
		(3 "B.Mask" user "Board Geometry/Soldermask Bottom")
		(17 "Dwgs.User" user "User.Drawings")
		(19 "Cmts.User" user "User.Comments")
		(21 "Eco1.User" user "User.Eco1")
		(23 "Eco2.User" user "User.Eco2")
		(25 "Edge.Cuts" user "Board Geometry/Outline")
		(27 "Margin" user)
		(31 "F.CrtYd" user "Package Geometry/Place Bound Top")
		(29 "B.CrtYd" user "Package Geometry/Place Bound Bottom")
		(35 "F.Fab" user "Ref Des/Assembly Top")
		(33 "B.Fab" user "Ref Des/Assembly Bottom")
	)
	(footprint ""
		(layer "B.Cu")
		(at 480.108006 -34.980118 -90)
		(property "Reference" "R2T52"
			(at 0 0 90)
			(layer "B.SilkS")
			(hide yes)
			(effects
				(font
					(size 1.27 1.27)
				)
				(justify mirror)
			)
		)
		(property "Value" ""
			(at 0 0 90)
			(layer "B.Fab")
			(effects
				(font
					(size 1.27 1.27)
				)
				(justify mirror)
			)
		)
		(duplicate_pad_numbers_are_jumpers no)
		(fp_poly
			(pts
				(xy 0.4953 -0.2032) (xy -0.4953 -0.2032) (xy -0.4953 1.6002) (xy 0.4953 1.6002)
			)
			(stroke
				(width 0)
				(type default)
			)
			(fill no)
			(layer "B.CrtYd")
		)
		(fp_line
			(start -0.4953 1.6002)
			(end 0.4953 1.6002)
			(stroke
				(width 0.1)
				(type default)
			)
			(layer "B.Fab")
		)
		(fp_line
			(start 0.4953 1.6002)
			(end 0.4953 -0.2032)
			(stroke
				(width 0.1)
				(type default)
			)
			(layer "B.Fab")
		)
		(fp_line
			(start -0.4953 -0.2032)
			(end -0.4953 1.6002)
			(stroke
				(width 0.1)
				(type default)
			)
			(layer "B.Fab")
		)
		(fp_line
			(start 0.4953 -0.2032)
			(end -0.4953 -0.2032)
			(stroke
				(width 0.1)
				(type default)
			)
			(layer "B.Fab")
		)
		(pad "1" smd rect
			(at 0 0 90)
			(size 0.762 0.889)
			(layers "B.Cu" "B.Mask" "B.Paste")
			(net "P3V3_STBY_MNG")
		)
		(pad "2" smd rect
			(at 0 1.397 90)
			(size 0.762 0.889)
			(layers "B.Cu" "B.Mask" "B.Paste")
			(net "P3V3_STBY_MNG_RMII")
		)
		(zone
			(layer "B.Cu")
			(hatch none 0.5)
			(connect_pads
				(clearance 0)
			)
			(min_thickness 0.25)
			(keepout
				(tracks allowed)
				(vias not_allowed)
				(pads allowed)
				(copperpour not_allowed)
				(footprints allowed)
			)
			(placement
				(enabled no)
				(sheetname "")
			)
			(fill
				(thermal_gap 0.5)
				(thermal_bridge_width 0.5)
				(island_removal_mode 0)
			)
			(polygon
				(pts
					(xy 479.155506 -35.361118) (xy 479.663506 -35.361118) (xy 479.663506 -34.599118) (xy 479.155506 -34.599118)
				)
			)
		)
		(zone
			(layer "B.Cu")
			(hatch none 0.5)
			(connect_pads
				(clearance 0)
			)
			(min_thickness 0.25)
			(keepout
				(tracks not_allowed)
				(vias allowed)
				(pads allowed)
				(copperpour not_allowed)
				(footprints allowed)
			)
			(placement
				(enabled no)
				(sheetname "")
			)
			(fill
				(thermal_gap 0.5)
				(thermal_bridge_width 0.5)
				(island_removal_mode 0)
			)
			(polygon
				(pts
					(xy 479.155506 -34.599118) (xy 479.663506 -34.599118) (xy 479.663506 -35.361118) (xy 479.155506 -35.361118)
				)
			)
		)
	)
	(footprint ""
		(layer "B.Cu")
		(at 374.408446 -88.236806 180)
		(property "Reference" "R3N14"
			(at 0.8382 -0.67818 180)
			(unlocked yes)
			(layer "B.SilkS")
			(effects
				(font
					(size 0.4064 0.254)
					(thickness 0.1524)
				)
				(justify left mirror)
			)
		)
		(property "Value" ""
			(at 0 0 0)
			(layer "B.Fab")
			(effects
				(font
					(size 1.27 1.27)
				)
				(justify mirror)
			)
		)
		(duplicate_pad_numbers_are_jumpers no)
		(fp_poly
			(pts
				(xy 0.2794 -0.1016) (xy -0.2794 -0.1016) (xy -0.2794 0.9906) (xy 0.2794 0.9906)
			)
			(stroke
				(width 0)
				(type default)
			)
			(fill no)
			(layer "B.CrtYd")
		)
		(fp_line
			(start 0.2794 0.9906)
			(end -0.2794 0.9906)
			(stroke
				(width 0.1)
				(type default)
			)
			(layer "B.Fab")
		)
		(fp_line
			(start 0.2794 -0.1016)
			(end 0.2794 0.9906)
			(stroke
				(width 0.1)
				(type default)
			)
			(layer "B.Fab")
		)
		(fp_line
			(start -0.2794 0.9906)
			(end -0.2794 -0.1016)
			(stroke
				(width 0.1)
				(type default)
			)
			(layer "B.Fab")
		)
		(fp_line
			(start -0.2794 -0.1016)
			(end 0.2794 -0.1016)
			(stroke
				(width 0.1)
				(type default)
			)
			(layer "B.Fab")
		)
		(pad "1" smd rect
			(at 0 0)
			(size 0.508 0.508)
			(layers "B.Cu" "B.Mask" "B.Paste")
			(net "H_PM_SYNC_GTL")
		)
		(pad "2" smd rect
			(at 0 0.889)
			(size 0.508 0.508)
			(layers "B.Cu" "B.Mask" "B.Paste")
			(net "GND")
		)
		(zone
			(layer "B.Cu")
			(hatch none 0.5)
			(connect_pads
				(clearance 0)
			)
			(min_thickness 0.25)
			(keepout
				(tracks not_allowed)
				(vias allowed)
				(pads allowed)
				(copperpour not_allowed)
				(footprints allowed)
			)
			(placement
				(enabled no)
				(sheetname "")
			)
			(fill
				(thermal_gap 0.5)
				(thermal_bridge_width 0.5)
				(island_removal_mode 0)
			)
			(polygon
				(pts
					(xy 374.154446 -88.871806) (xy 374.662446 -88.871806) (xy 374.662446 -88.490806) (xy 374.154446 -88.490806)
				)
			)
		)
		(zone
			(layer "B.Cu")
			(hatch none 0.5)
			(connect_pads
				(clearance 0)
			)
			(min_thickness 0.25)
			(keepout
				(tracks allowed)
				(vias not_allowed)
				(pads allowed)
				(copperpour not_allowed)
				(footprints allowed)
			)
			(placement
				(enabled no)
				(sheetname "")
			)
			(fill
				(thermal_gap 0.5)
				(thermal_bridge_width 0.5)
				(island_removal_mode 0)
			)
			(polygon
				(pts
					(xy 374.154446 -88.490806) (xy 374.662446 -88.490806) (xy 374.662446 -88.871806) (xy 374.154446 -88.871806)
				)
			)
		)
	)
)
